(kicad_pcb
	(version 20260206)
	(generator "pcbnew")
	(generator_version "10.0")
	(general
		(thickness 1.6)
		(legacy_teardrops no)
	)
	(paper "A4")
	(title_block
		(title "03242023_DA0F0TMBIJ0_F0T_Motherboard_J_brd_V01_OCP.brd")
		(comment 1 "Grand Teton / footprints 978-983 of 6105")
	)
	(layers
		(0 "F.Cu" signal "TOP")
		(4 "In1.Cu" signal "GND")
		(6 "In2.Cu" signal "IN1")
		(8 "In3.Cu" signal "GND1")
		(10 "In4.Cu" signal "IN2")
		(12 "In5.Cu" signal "GND2")
		(14 "In6.Cu" signal "IN3")
		(16 "In7.Cu" signal "GND3")
		(18 "In8.Cu" signal "VCC")
		(20 "In9.Cu" signal "VCC1")
		(22 "In10.Cu" signal "GND4")
		(24 "In11.Cu" signal "IN4")
		(26 "In12.Cu" signal "GND5")
		(28 "In13.Cu" signal "IN5")
		(30 "In14.Cu" signal "GND6")
		(32 "In15.Cu" signal "IN6")
		(34 "In16.Cu" signal "GND7")
		(2 "B.Cu" signal "BOTTOM")
		(9 "F.Adhes" user "F.Adhesive")
		(11 "B.Adhes" user "B.Adhesive")
		(13 "F.Paste" user "Package Geometry/Pastemask Top")
		(15 "B.Paste" user "Package Geometry/Pastemask Bottom")
		(5 "F.SilkS" user "Ref Des/Silkscreen Top")
		(7 "B.SilkS" user "Ref Des/Silkscreen Bottom")
		(1 "F.Mask" user "Board Geometry/Soldermask Top")
		(3 "B.Mask" user "Board Geometry/Soldermask Bottom")
		(17 "Dwgs.User" user "User.Drawings")
		(19 "Cmts.User" user "User.Comments")
		(21 "Eco1.User" user "User.Eco1")
		(23 "Eco2.User" user "User.Eco2")
		(25 "Edge.Cuts" user "Board Geometry/Outline")
		(27 "Margin" user)
		(31 "F.CrtYd" user "Package Geometry/Place Bound Top")
		(29 "B.CrtYd" user "Package Geometry/Place Bound Bottom")
		(35 "F.Fab" user "Ref Des/Assembly Top")
		(33 "B.Fab" user "Ref Des/Assembly Bottom")
	)
	(footprint ""
		(layer "F.Cu")
		(at 193.38036 -121.884948)
		(property "Reference" "R2155"
			(at 0 0 0)
			(layer "F.SilkS")
			(hide yes)
			(effects
				(font
					(size 1.27 1.27)
				)
			)
		)
		(property "Value" ""
			(at 0 0 0)
			(layer "F.Fab")
			(effects
				(font
					(size 1.27 1.27)
				)
			)
		)
		(duplicate_pad_numbers_are_jumpers no)
		(fp_line
			(start -0.7874 -0.4064)
			(end 0.7874 -0.4064)
			(stroke
				(width 0.1524)
				(type default)
			)
			(layer "F.SilkS")
		)
		(fp_line
			(start -0.7874 0.4064)
			(end -0.7874 -0.4064)
			(stroke
				(width 0.1524)
				(type default)
			)
			(layer "F.SilkS")
		)
		(fp_line
			(start 0.7874 -0.4064)
			(end 0.7874 0.4064)
			(stroke
				(width 0.1524)
				(type default)
			)
			(layer "F.SilkS")
		)
		(fp_line
			(start 0.7874 0.4064)
			(end -0.7874 0.4064)
			(stroke
				(width 0.1524)
				(type default)
			)
			(layer "F.SilkS")
		)
		(fp_line
			(start -0.67945 -0.305054)
			(end -0.12065 -0.305054)
			(stroke
				(width 0.1)
				(type default)
			)
			(layer "F.Fab")
		)
		(fp_line
			(start -0.67945 0.3048)
			(end -0.67945 -0.305054)
			(stroke
				(width 0.1)
				(type default)
			)
			(layer "F.Fab")
		)
		(fp_line
			(start -0.12065 -0.305054)
			(end -0.12065 -0.2794)
			(stroke
				(width 0.1)
				(type default)
			)
			(layer "F.Fab")
		)
		(fp_line
			(start -0.12065 -0.2794)
			(end 0.12065 -0.2794)
			(stroke
				(width 0.1)
				(type default)
			)
			(layer "F.Fab")
		)
		(fp_line
			(start -0.12065 0.2794)
			(end -0.12065 0.3048)
			(stroke
				(width 0.1)
				(type default)
			)
			(layer "F.Fab")
		)
		(fp_line
			(start -0.12065 0.3048)
			(end -0.67945 0.3048)
			(stroke
				(width 0.1)
				(type default)
			)
			(layer "F.Fab")
		)
		(fp_line
			(start 0.120396 0.2794)
			(end -0.12065 0.2794)
			(stroke
				(width 0.1)
				(type default)
			)
			(layer "F.Fab")
		)
		(fp_line
			(start 0.120396 0.3048)
			(end 0.120396 0.2794)
			(stroke
				(width 0.1)
				(type default)
			)
			(layer "F.Fab")
		)
		(fp_line
			(start 0.12065 -0.3048)
			(end 0.67945 -0.3048)
			(stroke
				(width 0.1)
				(type default)
			)
			(layer "F.Fab")
		)
		(fp_line
			(start 0.12065 -0.2794)
			(end 0.12065 -0.3048)
			(stroke
				(width 0.1)
				(type default)
			)
			(layer "F.Fab")
		)
		(fp_line
			(start 0.67945 -0.3048)
			(end 0.67945 0.3048)
			(stroke
				(width 0.1)
				(type default)
			)
			(layer "F.Fab")
		)
		(fp_line
			(start 0.67945 0.3048)
			(end 0.120396 0.3048)
			(stroke
				(width 0.1)
				(type default)
			)
			(layer "F.Fab")
		)
		(pad "1" smd circle
			(at -0.40005 0)
			(size 0 0)
			(layers "F.Cu" "F.Mask" "F.Paste")
			(net "FM_BMC_READY_R_PLD_N")
		)
		(pad "2" smd circle
			(at 0.40005 0)
			(size 0 0)
			(layers "F.Cu" "F.Mask" "F.Paste")
			(net "FM_BMC_READY_R_N")
		)
	)
	(footprint ""
		(layer "F.Cu")
		(at 170.23588 -434.939948 180)
		(property "Reference" "R3456"
			(at 0 0 180)
			(layer "F.SilkS")
			(hide yes)
			(effects
				(font
					(size 1.27 1.27)
				)
			)
		)
		(property "Value" ""
			(at 0 0 180)
			(layer "F.Fab")
			(effects
				(font
					(size 1.27 1.27)
				)
			)
		)
		(duplicate_pad_numbers_are_jumpers no)
		(fp_line
			(start 0.7874 0.4064)
			(end -0.7874 0.4064)
			(stroke
				(width 0.1524)
				(type default)
			)
			(layer "F.SilkS")
		)
		(fp_line
			(start 0.7874 -0.4064)
			(end 0.7874 0.4064)
			(stroke
				(width 0.1524)
				(type default)
			)
			(layer "F.SilkS")
		)
		(fp_line
			(start -0.7874 0.4064)
			(end -0.7874 -0.4064)
			(stroke
				(width 0.1524)
				(type default)
			)
			(layer "F.SilkS")
		)
		(fp_line
			(start -0.7874 -0.4064)
			(end 0.7874 -0.4064)
			(stroke
				(width 0.1524)
				(type default)
			)
			(layer "F.SilkS")
		)
		(fp_line
			(start 0.67945 0.3048)
			(end 0.120396 0.3048)
			(stroke
				(width 0.1)
				(type default)
			)
			(layer "F.Fab")
		)
		(fp_line
			(start 0.67945 -0.3048)
			(end 0.67945 0.3048)
			(stroke
				(width 0.1)
				(type default)
			)
			(layer "F.Fab")
		)
		(fp_line
			(start 0.12065 -0.2794)
			(end 0.12065 -0.3048)
			(stroke
				(width 0.1)
				(type default)
			)
			(layer "F.Fab")
		)
		(fp_line
			(start 0.12065 -0.3048)
			(end 0.67945 -0.3048)
			(stroke
				(width 0.1)
				(type default)
			)
			(layer "F.Fab")
		)
		(fp_line
			(start 0.120396 0.3048)
			(end 0.120396 0.2794)
			(stroke
				(width 0.1)
				(type default)
			)
			(layer "F.Fab")
		)
		(fp_line
			(start 0.120396 0.2794)
			(end -0.12065 0.2794)
			(stroke
				(width 0.1)
				(type default)
			)
			(layer "F.Fab")
		)
		(fp_line
			(start -0.12065 0.3048)
			(end -0.67945 0.3048)
			(stroke
				(width 0.1)
				(type default)
			)
			(layer "F.Fab")
		)
		(fp_line
			(start -0.12065 0.2794)
			(end -0.12065 0.3048)
			(stroke
				(width 0.1)
				(type default)
			)
			(layer "F.Fab")
		)
		(fp_line
			(start -0.12065 -0.2794)
			(end 0.12065 -0.2794)
			(stroke
				(width 0.1)
				(type default)
			)
			(layer "F.Fab")
		)
		(fp_line
			(start -0.12065 -0.305054)
			(end -0.12065 -0.2794)
			(stroke
				(width 0.1)
				(type default)
			)
			(layer "F.Fab")
		)
		(fp_line
			(start -0.67945 0.3048)
			(end -0.67945 -0.305054)
			(stroke
				(width 0.1)
				(type default)
			)
			(layer "F.Fab")
		)
		(fp_line
			(start -0.67945 -0.305054)
			(end -0.12065 -0.305054)
			(stroke
				(width 0.1)
				(type default)
			)
			(layer "F.Fab")
		)
		(pad "1" smd circle
			(at -0.40005 0 180)
			(size 0 0)
			(layers "F.Cu" "F.Mask" "F.Paste")
			(net "P3V3_AUX")
		)
		(pad "2" smd circle
			(at 0.40005 0 180)
			(size 0 0)
			(layers "F.Cu" "F.Mask" "F.Paste")
			(net "GPU_BASE_STBY_EN_BUF_R")
		)
	)
	(footprint ""
		(layer "F.Cu")
		(at 193.38036 -119.344948)
		(property "Reference" "R1434"
			(at 0 0 0)
			(layer "F.SilkS")
			(hide yes)
			(effects
				(font
					(size 1.27 1.27)
				)
			)
		)
		(property "Value" ""
			(at 0 0 0)
			(layer "F.Fab")
			(effects
				(font
					(size 1.27 1.27)
				)
			)
		)
		(duplicate_pad_numbers_are_jumpers no)
		(fp_line
			(start -0.7874 -0.4064)
			(end 0.7874 -0.4064)
			(stroke
				(width 0.1524)
				(type default)
			)
			(layer "F.SilkS")
		)
		(fp_line
			(start -0.7874 0.4064)
			(end -0.7874 -0.4064)
			(stroke
				(width 0.1524)
				(type default)
			)
			(layer "F.SilkS")
		)
		(fp_line
			(start 0.7874 -0.4064)
			(end 0.7874 0.4064)
			(stroke
				(width 0.1524)
				(type default)
			)
			(layer "F.SilkS")
		)
		(fp_line
			(start 0.7874 0.4064)
			(end -0.7874 0.4064)
			(stroke
				(width 0.1524)
				(type default)
			)
			(layer "F.SilkS")
		)
		(fp_line
			(start -0.67945 -0.305054)
			(end -0.12065 -0.305054)
			(stroke
				(width 0.1)
				(type default)
			)
			(layer "F.Fab")
		)
		(fp_line
			(start -0.67945 0.3048)
			(end -0.67945 -0.305054)
			(stroke
				(width 0.1)
				(type default)
			)
			(layer "F.Fab")
		)
		(fp_line
			(start -0.12065 -0.305054)
			(end -0.12065 -0.2794)
			(stroke
				(width 0.1)
				(type default)
			)
			(layer "F.Fab")
		)
		(fp_line
			(start -0.12065 -0.2794)
			(end 0.12065 -0.2794)
			(stroke
				(width 0.1)
				(type default)
			)
			(layer "F.Fab")
		)
		(fp_line
			(start -0.12065 0.2794)
			(end -0.12065 0.3048)
			(stroke
				(width 0.1)
				(type default)
			)
			(layer "F.Fab")
		)
		(fp_line
			(start -0.12065 0.3048)
			(end -0.67945 0.3048)
			(stroke
				(width 0.1)
				(type default)
			)
			(layer "F.Fab")
		)
		(fp_line
			(start 0.120396 0.2794)
			(end -0.12065 0.2794)
			(stroke
				(width 0.1)
				(type default)
			)
			(layer "F.Fab")
		)
		(fp_line
			(start 0.120396 0.3048)
			(end 0.120396 0.2794)
			(stroke
				(width 0.1)
				(type default)
			)
			(layer "F.Fab")
		)
		(fp_line
			(start 0.12065 -0.3048)
			(end 0.67945 -0.3048)
			(stroke
				(width 0.1)
				(type default)
			)
			(layer "F.Fab")
		)
		(fp_line
			(start 0.12065 -0.2794)
			(end 0.12065 -0.3048)
			(stroke
				(width 0.1)
				(type default)
			)
			(layer "F.Fab")
		)
		(fp_line
			(start 0.67945 -0.3048)
			(end 0.67945 0.3048)
			(stroke
				(width 0.1)
				(type default)
			)
			(layer "F.Fab")
		)
		(fp_line
			(start 0.67945 0.3048)
			(end 0.120396 0.3048)
			(stroke
				(width 0.1)
				(type default)
			)
			(layer "F.Fab")
		)
		(pad "1" smd circle
			(at -0.40005 0)
			(size 0 0)
			(layers "F.Cu" "F.Mask" "F.Paste")
			(net "FM_SYS_THROTTLE_R_N")
		)
		(pad "2" smd circle
			(at 0.40005 0)
			(size 0 0)
			(layers "F.Cu" "F.Mask" "F.Paste")
			(net "P3V3_AUX")
		)
	)
	(footprint ""
		(layer "F.Cu")
		(at 118.542816 -240.277142 90)
		(property "Reference" "C426"
			(at 0 0 90)
			(layer "F.SilkS")
			(hide yes)
			(effects
				(font
					(size 1.27 1.27)
				)
			)
		)
		(property "Value" ""
			(at 0 0 90)
			(layer "F.Fab")
			(effects
				(font
					(size 1.27 1.27)
				)
			)
		)
		(duplicate_pad_numbers_are_jumpers no)
		(fp_line
			(start 0.7874 -0.4064)
			(end 0.7874 0.4064)
			(stroke
				(width 0.1524)
				(type default)
			)
			(layer "F.SilkS")
		)
		(fp_line
			(start -0.7874 -0.4064)
			(end 0.7874 -0.4064)
			(stroke
				(width 0.1524)
				(type default)
			)
			(layer "F.SilkS")
		)
		(fp_line
			(start 0.7874 0.4064)
			(end -0.7874 0.4064)
			(stroke
				(width 0.1524)
				(type default)
			)
			(layer "F.SilkS")
		)
		(fp_line
			(start -0.7874 0.4064)
			(end -0.7874 -0.4064)
			(stroke
				(width 0.1524)
				(type default)
			)
			(layer "F.SilkS")
		)
		(fp_line
			(start -0.12065 -0.305054)
			(end -0.12065 -0.2794)
			(stroke
				(width 0.1)
				(type default)
			)
			(layer "F.Fab")
		)
		(fp_line
			(start -0.67945 -0.305054)
			(end -0.12065 -0.305054)
			(stroke
				(width 0.1)
				(type default)
			)
			(layer "F.Fab")
		)
		(fp_line
			(start 0.67945 -0.3048)
			(end 0.67945 0.3048)
			(stroke
				(width 0.1)
				(type default)
			)
			(layer "F.Fab")
		)
		(fp_line
			(start 0.12065 -0.3048)
			(end 0.67945 -0.3048)
			(stroke
				(width 0.1)
				(type default)
			)
			(layer "F.Fab")
		)
		(fp_line
			(start 0.12065 -0.2794)
			(end 0.12065 -0.3048)
			(stroke
				(width 0.1)
				(type default)
			)
			(layer "F.Fab")
		)
		(fp_line
			(start -0.12065 -0.2794)
			(end 0.12065 -0.2794)
			(stroke
				(width 0.1)
				(type default)
			)
			(layer "F.Fab")
		)
		(fp_line
			(start 0.120396 0.2794)
			(end -0.12065 0.2794)
			(stroke
				(width 0.1)
				(type default)
			)
			(layer "F.Fab")
		)
		(fp_line
			(start -0.12065 0.2794)
			(end -0.12065 0.3048)
			(stroke
				(width 0.1)
				(type default)
			)
			(layer "F.Fab")
		)
		(fp_line
			(start 0.67945 0.3048)
			(end 0.120396 0.3048)
			(stroke
				(width 0.1)
				(type default)
			)
			(layer "F.Fab")
		)
		(fp_line
			(start 0.120396 0.3048)
			(end 0.120396 0.2794)
			(stroke
				(width 0.1)
				(type default)
			)
			(layer "F.Fab")
		)
		(fp_line
			(start -0.12065 0.3048)
			(end -0.67945 0.3048)
			(stroke
				(width 0.1)
				(type default)
			)
			(layer "F.Fab")
		)
		(fp_line
			(start -0.67945 0.3048)
			(end -0.67945 -0.305054)
			(stroke
				(width 0.1)
				(type default)
			)
			(layer "F.Fab")
		)
		(pad "1" smd circle
			(at -0.40005 0 90)
			(size 0 0)
			(layers "F.Cu" "F.Mask" "F.Paste")
			(net "PVCCFA_EHV_FIVRA_CPU1")
		)
		(pad "2" smd circle
			(at 0.40005 0 90)
			(size 0 0)
			(layers "F.Cu" "F.Mask" "F.Paste")
			(net "GND")
		)
	)
	(footprint ""
		(layer "F.Cu")
		(at 27.0383 -128.364996 180)
		(property "Reference" "PC474"
			(at 0 0 180)
			(layer "F.SilkS")
			(hide yes)
			(effects
				(font
					(size 1.27 1.27)
				)
			)
		)
		(property "Value" ""
			(at 0 0 180)
			(layer "F.Fab")
			(effects
				(font
					(size 1.27 1.27)
				)
			)
		)
		(duplicate_pad_numbers_are_jumpers no)
		(fp_line
			(start 0.7874 0.4064)
			(end -0.7874 0.4064)
			(stroke
				(width 0.1524)
				(type default)
			)
			(layer "F.SilkS")
		)
		(fp_line
			(start 0.7874 -0.4064)
			(end 0.7874 0.4064)
			(stroke
				(width 0.1524)
				(type default)
			)
			(layer "F.SilkS")
		)
		(fp_line
			(start -0.7874 0.4064)
			(end -0.7874 -0.4064)
			(stroke
				(width 0.1524)
				(type default)
			)
			(layer "F.SilkS")
		)
		(fp_line
			(start -0.7874 -0.4064)
			(end 0.7874 -0.4064)
			(stroke
				(width 0.1524)
				(type default)
			)
			(layer "F.SilkS")
		)
		(fp_line
			(start 0.67945 0.3048)
			(end 0.120396 0.3048)
			(stroke
				(width 0.1)
				(type default)
			)
			(layer "F.Fab")
		)
		(fp_line
			(start 0.67945 -0.3048)
			(end 0.67945 0.3048)
			(stroke
				(width 0.1)
				(type default)
			)
			(layer "F.Fab")
		)
		(fp_line
			(start 0.12065 -0.2794)
			(end 0.12065 -0.3048)
			(stroke
				(width 0.1)
				(type default)
			)
			(layer "F.Fab")
		)
		(fp_line
			(start 0.12065 -0.3048)
			(end 0.67945 -0.3048)
			(stroke
				(width 0.1)
				(type default)
			)
			(layer "F.Fab")
		)
		(fp_line
			(start 0.120396 0.3048)
			(end 0.120396 0.2794)
			(stroke
				(width 0.1)
				(type default)
			)
			(layer "F.Fab")
		)
		(fp_line
			(start 0.120396 0.2794)
			(end -0.12065 0.2794)
			(stroke
				(width 0.1)
				(type default)
			)
			(layer "F.Fab")
		)
		(fp_line
			(start -0.12065 0.3048)
			(end -0.67945 0.3048)
			(stroke
				(width 0.1)
				(type default)
			)
			(layer "F.Fab")
		)
		(fp_line
			(start -0.12065 0.2794)
			(end -0.12065 0.3048)
			(stroke
				(width 0.1)
				(type default)
			)
			(layer "F.Fab")
		)
		(fp_line
			(start -0.12065 -0.2794)
			(end 0.12065 -0.2794)
			(stroke
				(width 0.1)
				(type default)
			)
			(layer "F.Fab")
		)
		(fp_line
			(start -0.12065 -0.305054)
			(end -0.12065 -0.2794)
			(stroke
				(width 0.1)
				(type default)
			)
			(layer "F.Fab")
		)
		(fp_line
			(start -0.67945 0.3048)
			(end -0.67945 -0.305054)
			(stroke
				(width 0.1)
				(type default)
			)
			(layer "F.Fab")
		)
		(fp_line
			(start -0.67945 -0.305054)
			(end -0.12065 -0.305054)
			(stroke
				(width 0.1)
				(type default)
			)
			(layer "F.Fab")
		)
		(pad "1" smd circle
			(at -0.40005 0 180)
			(size 0 0)
			(layers "F.Cu" "F.Mask" "F.Paste")
			(net "PVCCINFAON_CPU1_VIN_CSNIN")
		)
		(pad "2" smd circle
			(at 0.40005 0 180)
			(size 0 0)
			(layers "F.Cu" "F.Mask" "F.Paste")
			(net "GND")
		)
	)
	(footprint ""
		(layer "F.Cu")
		(at 69.036438 -31.887922 90)
		(property "Reference" "PC2164"
			(at 0 0 90)
			(layer "F.SilkS")
			(hide yes)
			(effects
				(font
					(size 1.27 1.27)
				)
			)
		)
		(property "Value" ""
			(at 0 0 90)
			(layer "F.Fab")
			(effects
				(font
					(size 1.27 1.27)
				)
			)
		)
		(duplicate_pad_numbers_are_jumpers no)
		(fp_line
			(start 0.7874 -0.4064)
			(end 0.7874 0.4064)
			(stroke
				(width 0.1524)
				(type default)
			)
			(layer "F.SilkS")
		)
		(fp_line
			(start -0.7874 -0.4064)
			(end 0.7874 -0.4064)
			(stroke
				(width 0.1524)
				(type default)
			)
			(layer "F.SilkS")
		)
		(fp_line
			(start 0.7874 0.4064)
			(end -0.7874 0.4064)
			(stroke
				(width 0.1524)
				(type default)
			)
			(layer "F.SilkS")
		)
		(fp_line
			(start -0.7874 0.4064)
			(end -0.7874 -0.4064)
			(stroke
				(width 0.1524)
				(type default)
			)
			(layer "F.SilkS")
		)
		(fp_line
			(start -0.12065 -0.305054)
			(end -0.12065 -0.2794)
			(stroke
				(width 0.1)
				(type default)
			)
			(layer "F.Fab")
		)
		(fp_line
			(start -0.67945 -0.305054)
			(end -0.12065 -0.305054)
			(stroke
				(width 0.1)
				(type default)
			)
			(layer "F.Fab")
		)
		(fp_line
			(start 0.67945 -0.3048)
			(end 0.67945 0.3048)
			(stroke
				(width 0.1)
				(type default)
			)
			(layer "F.Fab")
		)
		(fp_line
			(start 0.12065 -0.3048)
			(end 0.67945 -0.3048)
			(stroke
				(width 0.1)
				(type default)
			)
			(layer "F.Fab")
		)
		(fp_line
			(start 0.12065 -0.2794)
			(end 0.12065 -0.3048)
			(stroke
				(width 0.1)
				(type default)
			)
			(layer "F.Fab")
		)
		(fp_line
			(start -0.12065 -0.2794)
			(end 0.12065 -0.2794)
			(stroke
				(width 0.1)
				(type default)
			)
			(layer "F.Fab")
		)
		(fp_line
			(start 0.120396 0.2794)
			(end -0.12065 0.2794)
			(stroke
				(width 0.1)
				(type default)
			)
			(layer "F.Fab")
		)
		(fp_line
			(start -0.12065 0.2794)
			(end -0.12065 0.3048)
			(stroke
				(width 0.1)
				(type default)
			)
			(layer "F.Fab")
		)
		(fp_line
			(start 0.67945 0.3048)
			(end 0.120396 0.3048)
			(stroke
				(width 0.1)
				(type default)
			)
			(layer "F.Fab")
		)
		(fp_line
			(start 0.120396 0.3048)
			(end 0.120396 0.2794)
			(stroke
				(width 0.1)
				(type default)
			)
			(layer "F.Fab")
		)
		(fp_line
			(start -0.12065 0.3048)
			(end -0.67945 0.3048)
			(stroke
				(width 0.1)
				(type default)
			)
			(layer "F.Fab")
		)
		(fp_line
			(start -0.67945 0.3048)
			(end -0.67945 -0.305054)
			(stroke
				(width 0.1)
				(type default)
			)
			(layer "F.Fab")
		)
		(pad "1" smd circle
			(at -0.40005 0 90)
			(size 0 0)
			(layers "F.Cu" "F.Mask" "F.Paste")
			(net "P12V_OCP_TIMER_2")
		)
		(pad "2" smd circle
			(at 0.40005 0 90)
			(size 0 0)
			(layers "F.Cu" "F.Mask" "F.Paste")
			(net "GND")
		)
	)
)
